# T6G (Grand Teton) — schematic netlist excerpt (pin names and nets, part order shuffled) for the footprints in the layout excerpt that follows; sources: Cadence DE-HDL packaged netlist, KiCad conversion of 04192023_DAF0TMB3IC0_F0TG_MB_C_brd_V02_OCP.brd

J21  SCONN288_DDR506112002KQ  IO  pkg DDR288S_1-1VXC  page 90
  VIN_BULK0  = P12V_MEM_CPU0
  RFU0  = NC
  VIN_MGMT  = P3V3_AUX
  HSCL  = I3C_SPD_DDRE_CPU0_SCL
  HSDA  = I3C_SPD_DDRE_CPU0_SDA
  VSS0  = GND
  DQ0_A  = M_E_CPU0_SA_DQ<0>
  VSS1  = GND
  DQ1_A  = M_E_CPU0_SA_DQ<1>
  VSS2  = GND
  DQS0_A_T  = M_E_CPU0_SA_DQS_DP<0>
  DQS0_A_C  = M_E_CPU0_SA_DQS_DN<0>
  VSS3  = GND
  DQ4_A  = M_E_CPU0_SA_DQ<4>
  VSS4  = GND
  DQ5_A  = M_E_CPU0_SA_DQ<5>
  VSS5  = GND
  DQ8_A  = M_E_CPU0_SA_DQ<8>
  VSS6  = GND
  DQ9_A  = M_E_CPU0_SA_DQ<9>
  VSS7  = GND
  DQS1_A_T  = M_E_CPU0_SA_DQS_DP<1>
  DQS1_A_C  = M_E_CPU0_SA_DQS_DN<1>
  VSS8  = GND
  DQ12_A  = M_E_CPU0_SA_DQ<12>
  VSS9  = GND
  DQ13_A  = M_E_CPU0_SA_DQ<13>
  VSS10  = GND
  DQ16_A  = M_E_CPU0_SA_DQ<16>
  VSS11  = GND
  DQ17_A  = M_E_CPU0_SA_DQ<17>
  VSS12  = GND
  DQS2_A_T  = M_E_CPU0_SA_DQS_DP<2>
  DQS2_A_C  = M_E_CPU0_SA_DQS_DN<2>
  VSS13  = GND
  DQ20_A  = M_E_CPU0_SA_DQ<20>
  VSS14  = GND
  DQ21_A  = M_E_CPU0_SA_DQ<21>
  VSS15  = GND
  DQ24_A  = M_E_CPU0_SA_DQ<24>
  VSS16  = GND
  DQ25_A  = M_E_CPU0_SA_DQ<25>
  VSS17  = GND
  DQS3_A_T  = M_E_CPU0_SA_DQS_DP<3>
  DQS3_A_C  = M_E_CPU0_SA_DQS_DN<3>
  VSS18  = GND
  DQ28_A  = M_E_CPU0_SA_DQ<28>
  VSS19  = GND
  DQ29_A  = M_E_CPU0_SA_DQ<29>
  VSS20  = GND
  CB0_A  = M_E_CPU0_SA_CB<0>
  VSS21  = GND
  CB1_A  = M_E_CPU0_SA_CB<1>
  VSS22  = GND
  DQS4_A_T  = M_E_CPU0_SA_DQS_DP<4>
  DQS4_A_C  = M_E_CPU0_SA_DQS_DN<4>
  VSS23  = GND
  CB4_A  = M_E_CPU0_SA_CB<4>
  VSS24  = GND
  CB5_A  = M_E_CPU0_SA_CB<5>
  VSS25  = GND
  ALERT_N  = M_E_CPU0_ALERT_N
  VSS26  = GND
  CS0_A_N  = M_E_CPU0_SA_CS_N<0>
  VSS27  = GND
  CA0_A  = M_E_CPU0_SA_CA<0>
  VSS28  = GND
  CA2_A  = M_E_CPU0_SA_CA<2>
  VSS29  = GND
  CA4_A  = M_E_CPU0_SA_CA<4>
  VSS30  = GND
  CA6_A  = M_E_CPU0_SA_CA<6>
  VSS31  = GND
  PAR_A  = M_E_CPU0_SA_PAR
  VSS32  = GND
  CA0_B  = M_E_CPU0_SB_CA<0>
  VSS33  = GND
  CA2_B  = M_E_CPU0_SB_CA<2>
  VSS34  = GND
  CA4_B  = M_E_CPU0_SB_CA<4>
  VSS35  = GND
  CA6_B  = M_E_CPU0_SB_CA<6>
  VSS36  = GND
  CS0_B_N  = M_E_CPU0_SB_CS_N<0>
  VSS37  = GND
  \lbd||rsp_a_n\  = M_E_CPU0_SA_RSP<0>
  \lbs||rsp_b_n\  = M_E_CPU0_SB_RSP<0>
  VSS38  = GND
  CB4_B  = M_E_CPU0_SB_CB<4>
  VSS39  = GND
  CB5_B  = M_E_CPU0_SB_CB<5>
  VSS40  = GND
  \dqs9_b_t||tdqs9_b_t||dbi4_b_n\  = M_E_CPU0_SB_DQS_DP<9>
  \dqs9_b_c||tdqs9_b_c\  = M_E_CPU0_SB_DQS_DN<9>
  VSS41  = GND
  CB0_B  = M_E_CPU0_SB_CB<0>
  VSS42  = GND
  CB1_B  = M_E_CPU0_SB_CB<1>
  VSS43  = GND
  DQ0_B  = M_E_CPU0_SB_DQ<0>
  VSS44  = GND
  DQ1_B  = M_E_CPU0_SB_DQ<1>
  VSS45  = GND
  DQS0_B_T  = M_E_CPU0_SB_DQS_DP<0>
  DQS0_B_C  = M_E_CPU0_SB_DQS_DN<0>
  VSS46  = GND
  DQ4_B  = M_E_CPU0_SB_DQ<4>
  VSS47  = GND
  DQ5_B  = M_E_CPU0_SB_DQ<5>
  VSS48  = GND
  DQ8_B  = M_E_CPU0_SB_DQ<8>
  VSS49  = GND
  DQ9_B  = M_E_CPU0_SB_DQ<9>
  VSS50  = GND
  DQS1_B_T  = M_E_CPU0_SB_DQS_DP<1>
  DQS1_B_C  = M_E_CPU0_SB_DQS_DN<1>
  VSS51  = GND
  DQ12_B  = M_E_CPU0_SB_DQ<12>
  VSS52  = GND
  DQ13_B  = M_E_CPU0_SB_DQ<13>
  VSS53  = GND
  DQ16_B  = M_E_CPU0_SB_DQ<16>
  VSS54  = GND
  DQ17_B  = M_E_CPU0_SB_DQ<17>
  VSS55  = GND
  DQS2_B_T  = M_E_CPU0_SB_DQS_DP<2>
  DQS2_B_C  = M_E_CPU0_SB_DQS_DN<2>
  VSS56  = GND
  DQ20_B  = M_E_CPU0_SB_DQ<20>
  VSS57  = GND
  DQ21_B  = M_E_CPU0_SB_DQ<21>
  VSS58  = GND
  DQ24_B  = M_E_CPU0_SB_DQ<24>
  VSS59  = GND
  DQ25_B  = M_E_CPU0_SB_DQ<25>
  VSS60  = GND
  DQS3_B_T  = M_E_CPU0_SB_DQS_DP<3>
  DQS3_B_C  = M_E_CPU0_SB_DQS_DN<3>
  VSS61  = GND
  DQ28_B  = M_E_CPU0_SB_DQ<28>
  VSS62  = GND
  DQ29_B  = M_E_CPU0_SB_DQ<29>
  VSS63  = GND
  RFU1  = NC
  VIN_BULK1  = P12V_MEM_CPU0
  VIN_BULK2  = P12V_MEM_CPU0
  \pwr_good||fail_n\  = PWRGD_CHE_CPU0_DIMM
  HAS  = PD_CHE_CPU0_DIMM_SAA
  RFU2  = NC
  RFU3  = NC
  VSS64  = GND
  DQ2_A  = M_E_CPU0_SA_DQ<2>
  VSS65  = GND
  DQ3_A  = M_E_CPU0_SA_DQ<3>
  VSS66  = GND
  \dqs5_a_c||tdqs5_a_c||dqs5_a_t||tdqs5_a_t\  = M_E_CPU0_SA_DQS_DN<5>
  \dqs5_a_t||tdqs5_a_t\  = M_E_CPU0_SA_DQS_DP<5>
  VSS67  = GND
  DQ6_A  = M_E_CPU0_SA_DQ<6>
  VSS68  = GND
  DQ7_A  = M_E_CPU0_SA_DQ<7>
  VSS69  = GND
  DQ10_A  = M_E_CPU0_SA_DQ<10>
  VSS70  = GND
  DQ11_A  = M_E_CPU0_SA_DQ<11>
  VSS71  = GND
  \dqs6_a_c||tdqs6_a_c||dqs6_a_t||tdqs6_a_t\  = M_E_CPU0_SA_DQS_DN<6>
  \dqs6_a_t||tdqs6_a_t\  = M_E_CPU0_SA_DQS_DP<6>
  VSS72  = GND
  DQ14_A  = M_E_CPU0_SA_DQ<14>
  VSS73  = GND
  DQ15_A  = M_E_CPU0_SA_DQ<15>
  VSS74  = GND
  DQ18_A  = M_E_CPU0_SA_DQ<18>
  VSS75  = GND
  DQ19_A  = M_E_CPU0_SA_DQ<19>
  VSS76  = GND
  \dqs7_a_c||tdqs7_a_c\  = M_E_CPU0_SA_DQS_DN<7>
  \dqs7_a_t||tdqs7_a_t\  = M_E_CPU0_SA_DQS_DP<7>
  VSS77  = GND
  DQ22_A  = M_E_CPU0_SA_DQ<22>
  VSS78  = GND
  DQ23_A  = M_E_CPU0_SA_DQ<23>
  VSS79  = GND
  DQ26_A  = M_E_CPU0_SA_DQ<26>
  VSS80  = GND
  DQ27_A  = M_E_CPU0_SA_DQ<27>
  VSS81  = GND
  \dqs8_a_c||tdqs8_a_c\  = M_E_CPU0_SA_DQS_DN<8>
  \dqs8_a_t||tdqs8_a_t\  = M_E_CPU0_SA_DQS_DP<8>
  VSS82  = GND
  DQ30_A  = M_E_CPU0_SA_DQ<30>
  VSS83  = GND
  DQ31_A  = M_E_CPU0_SA_DQ<31>
  VSS84  = GND
  CB2_A  = M_E_CPU0_SA_CB<2>
  VSS85  = GND
  CB3_A  = M_E_CPU0_SA_CB<3>
  VSS86  = GND
  \dqs9_a_c||tdqs9_a_c\  = M_E_CPU0_SA_DQS_DN<9>
  \dqs9_a_t||tdqs9_a_t\  = M_E_CPU0_SA_DQS_DP<9>
  VSS87  = GND
  CB6_A  = M_E_CPU0_SA_CB<6>
  VSS88  = GND
  CB7_A  = M_E_CPU0_SA_CB<7>
  VSS89  = GND
  RESET_N  = M_E_CPU0_RESET_N
  VSS90  = GND
  CS1_A_N  = M_E_CPU0_SA_CS_N<1>
  VSS91  = GND
  CA1_A  = M_E_CPU0_SA_CA<1>
  VSS92  = GND
  CA3_A  = M_E_CPU0_SA_CA<3>
  VSS93  = GND
  CA5_A  = M_E_CPU0_SA_CA<5>
  VSS94  = GND
  CK_T  = M_E_CPU0_CLK_DP<0>
  CK_C  = M_E_CPU0_CLK_DN<0>
  VSS95  = GND
  RFU4  = NC
  CA1_B  = M_E_CPU0_SB_CA<1>
  VSS96  = GND
  CA3_B  = M_E_CPU0_SB_CA<3>
  VSS97  = GND
  CA5_B  = M_E_CPU0_SB_CA<5>
  VSS98  = GND
  PAR_B  = M_E_CPU0_SB_PAR
  VSS99  = GND
  CS1_B_N  = M_E_CPU0_SB_CS_N<1>
  VSS100  = GND
  RFU5  = NC
  RFU6  = NC
  VSS101  = GND
  CB6_B  = M_E_CPU0_SB_CB<6>
  VSS102  = GND
  CB7_B  = M_E_CPU0_SB_CB<7>
  VSS103  = GND
  DQS4_B_C  = M_E_CPU0_SB_DQS_DN<4>
  DQS4_B_T  = M_E_CPU0_SB_DQS_DP<4>
  VSS104  = GND
  CB2_B  = M_E_CPU0_SB_CB<2>
  VSS105  = GND
  CB3_B  = M_E_CPU0_SB_CB<3>
  VSS106  = GND
  DQ2_B  = M_E_CPU0_SB_DQ<2>
  VSS107  = GND
  DQ3_B  = M_E_CPU0_SB_DQ<3>
  VSS108  = GND
  \dqs5_b_c||tdqs5_b_c\  = M_E_CPU0_SB_DQS_DN<5>
  \dqs5_b_t||tdqs5_b_t\  = M_E_CPU0_SB_DQS_DP<5>
  VSS109  = GND
  DQ6_B  = M_E_CPU0_SB_DQ<6>
  VSS110  = GND
  DQ7_B  = M_E_CPU0_SB_DQ<7>
  VSS111  = GND
  DQ10_B  = M_E_CPU0_SB_DQ<10>
  VSS112  = GND
  DQ11_B  = M_E_CPU0_SB_DQ<11>
  VSS113  = GND
  \dqs6_b_c||tdqs6_b_c\  = M_E_CPU0_SB_DQS_DN<6>
  \dqs6_b_t||tdqs6_b_t\  = M_E_CPU0_SB_DQS_DP<6>
  VSS114  = GND
  DQ14_B  = M_E_CPU0_SB_DQ<14>
  VSS115  = GND
  DQ15_B  = M_E_CPU0_SB_DQ<15>
  VSS116  = GND
  DQ18_B  = M_E_CPU0_SB_DQ<18>
  VSS117  = GND
  DQ19_B  = M_E_CPU0_SB_DQ<19>
  VSS118  = GND
  \dqs7_b_c||tdqs7_b_c\  = M_E_CPU0_SB_DQS_DN<7>
  \dqs7_b_t||tdqs7_b_t\  = M_E_CPU0_SB_DQS_DP<7>
  VSS119  = GND
  DQ22_B  = M_E_CPU0_SB_DQ<22>
  VSS120  = GND
  DQ23_B  = M_E_CPU0_SB_DQ<23>
  VSS121  = GND
  DQ26_B  = M_E_CPU0_SB_DQ<26>
  VSS122  = GND
  DQ27_B  = M_E_CPU0_SB_DQ<27>
  VSS123  = GND
  \dqs8_b_c||tdqs8_b_c\  = M_E_CPU0_SB_DQS_DN<8>
  \dqs8_b_t||tdqs8_b_t\  = M_E_CPU0_SB_DQS_DP<8>
  VSS124  = GND
  DQ30_B  = M_E_CPU0_SB_DQ<30>
  VSS125  = GND
  DQ31_B  = M_E_CPU0_SB_DQ<31>
  VSS126  = GND
  G1  = GND
  G2  = GND
  G3  = GND

(kicad_pcb
	(version 20260206)
	(generator "pcbnew")
	(generator_version "10.0")
	(general
		(thickness 1.6)
		(legacy_teardrops no)
	)
	(paper "A4")
	(title_block
		(title "04192023_DAF0TMB3IC0_F0TG_MB_C_brd_V02_OCP.brd")
		(comment 1 "Grand Teton / footprint 3 of 8354 (J21), pads 1-46 of 291")
	)
	(layers
		(0 "F.Cu" signal "TOP")
		(4 "In1.Cu" signal "GND")
		(6 "In2.Cu" signal "IN1")
		(8 "In3.Cu" signal "GND1")
		(10 "In4.Cu" signal "IN2")
		(12 "In5.Cu" signal "GND2")
		(14 "In6.Cu" signal "IN3")
		(16 "In7.Cu" signal "GND3")
		(18 "In8.Cu" signal "VCC")
		(20 "In9.Cu" signal "VCC1")
		(22 "In10.Cu" signal "GND4")
		(24 "In11.Cu" signal "IN4")
		(26 "In12.Cu" signal "GND5")
		(28 "In13.Cu" signal "IN5")
		(30 "In14.Cu" signal "GND6")
		(32 "In15.Cu" signal "IN6")
		(34 "In16.Cu" signal "GND7")
		(2 "B.Cu" signal "BOTTOM")
		(9 "F.Adhes" user "F.Adhesive")
		(11 "B.Adhes" user "B.Adhesive")
		(13 "F.Paste" user "Package Geometry/Pastemask Top")
		(15 "B.Paste" user "Package Geometry/Pastemask Bottom")
		(5 "F.SilkS" user "Ref Des/Silkscreen Top")
		(7 "B.SilkS" user "Ref Des/Silkscreen Bottom")
		(1 "F.Mask" user "Board Geometry/Soldermask Top")
		(3 "B.Mask" user "Board Geometry/Soldermask Bottom")
		(17 "Dwgs.User" user "User.Drawings")
		(19 "Cmts.User" user "User.Comments")
		(21 "Eco1.User" user "User.Eco1")
		(23 "Eco2.User" user "User.Eco2")
		(25 "Edge.Cuts" user "Board Geometry/Outline")
		(27 "Margin" user)
		(31 "F.CrtYd" user "Package Geometry/Place Bound Top")
		(29 "B.CrtYd" user "Package Geometry/Place Bound Bottom")
		(35 "F.Fab" user "Ref Des/Assembly Top")
		(33 "B.Fab" user "Ref Des/Assembly Bottom")
	)
	(footprint ""
		(layer "F.Cu")
		(at 275.142198 -255.560068 180)
		(property "Reference" "J21"
			(at -2.2098 -81.984088 0)
			(unlocked yes)
			(layer "F.SilkS")
			(effects
				(font
					(size 0.7874 0.5842)
					(thickness 0.1524)
				)
			)
		)
		(property "Value" ""
			(at 0 0 180)
			(layer "F.Fab")
			(effects
				(font
					(size 1.27 1.27)
				)
			)
		)
		(duplicate_pad_numbers_are_jumpers no)
		(pad "1" smd rect
			(at -2.050034 -63.324994 90)
			(size 0.519938 1.4986)
			(layers "F.Cu" "F.Mask" "F.Paste")
			(net "P12V_MEM_CPU0")
		)
		(pad "2" smd rect
			(at -2.050034 -62.47511 90)
			(size 0.519938 1.4986)
			(layers "F.Cu" "F.Mask" "F.Paste")
			(net "Net_2305")
		)
		(pad "3" smd rect
			(at -2.050034 -61.624972 90)
			(size 0.519938 1.4986)
			(layers "F.Cu" "F.Mask" "F.Paste")
			(net "P3V3_AUX")
		)
		(pad "4" smd rect
			(at -2.050034 -60.775088 90)
			(size 0.519938 1.4986)
			(layers "F.Cu" "F.Mask" "F.Paste")
			(net "I3C_SPD_DDRE_CPU0_SCL")
		)
		(pad "5" smd rect
			(at -2.050034 -59.92495 90)
			(size 0.519938 1.4986)
			(layers "F.Cu" "F.Mask" "F.Paste")
			(net "I3C_SPD_DDRE_CPU0_SDA")
		)
		(pad "6" smd rect
			(at -2.050034 -59.075066 90)
			(size 0.519938 1.4986)
			(layers "F.Cu" "F.Mask" "F.Paste")
			(net "GND")
		)
		(pad "7" smd rect
			(at -2.050034 -58.224928 90)
			(size 0.519938 1.4986)
			(layers "F.Cu" "F.Mask" "F.Paste")
			(net "M_E_CPU0_SA_DQ<0>")
		)
		(pad "8" smd rect
			(at -2.050034 -57.375044 90)
			(size 0.519938 1.4986)
			(layers "F.Cu" "F.Mask" "F.Paste")
			(net "GND")
		)
		(pad "9" smd rect
			(at -2.050034 -56.524906 90)
			(size 0.519938 1.4986)
			(layers "F.Cu" "F.Mask" "F.Paste")
			(net "M_E_CPU0_SA_DQ<1>")
		)
		(pad "10" smd rect
			(at -2.050034 -55.675022 90)
			(size 0.519938 1.4986)
			(layers "F.Cu" "F.Mask" "F.Paste")
			(net "GND")
		)
		(pad "11" smd rect
			(at -2.050034 -54.824884 90)
			(size 0.519938 1.4986)
			(layers "F.Cu" "F.Mask" "F.Paste")
			(net "M_E_CPU0_SA_DQS_DP<0>")
		)
		(pad "12" smd rect
			(at -2.050034 -53.975 90)
			(size 0.519938 1.4986)
			(layers "F.Cu" "F.Mask" "F.Paste")
			(net "M_E_CPU0_SA_DQS_DN<0>")
		)
		(pad "13" smd rect
			(at -2.050034 -53.125116 90)
			(size 0.519938 1.4986)
			(layers "F.Cu" "F.Mask" "F.Paste")
			(net "GND")
		)
		(pad "14" smd rect
			(at -2.050034 -52.274978 90)
			(size 0.519938 1.4986)
			(layers "F.Cu" "F.Mask" "F.Paste")
			(net "M_E_CPU0_SA_DQ<4>")
		)
		(pad "15" smd rect
			(at -2.050034 -51.425094 90)
			(size 0.519938 1.4986)
			(layers "F.Cu" "F.Mask" "F.Paste")
			(net "GND")
		)
		(pad "16" smd rect
			(at -2.050034 -50.574956 90)
			(size 0.519938 1.4986)
			(layers "F.Cu" "F.Mask" "F.Paste")
			(net "M_E_CPU0_SA_DQ<5>")
		)
		(pad "17" smd rect
			(at -2.050034 -49.725072 90)
			(size 0.519938 1.4986)
			(layers "F.Cu" "F.Mask" "F.Paste")
			(net "GND")
		)
		(pad "18" smd rect
			(at -2.050034 -48.874934 90)
			(size 0.519938 1.4986)
			(layers "F.Cu" "F.Mask" "F.Paste")
			(net "M_E_CPU0_SA_DQ<8>")
		)
		(pad "19" smd rect
			(at -2.050034 -48.02505 90)
			(size 0.519938 1.4986)
			(layers "F.Cu" "F.Mask" "F.Paste")
			(net "GND")
		)
		(pad "20" smd rect
			(at -2.050034 -47.174912 90)
			(size 0.519938 1.4986)
			(layers "F.Cu" "F.Mask" "F.Paste")
			(net "M_E_CPU0_SA_DQ<9>")
		)
		(pad "21" smd rect
			(at -2.050034 -46.325028 90)
			(size 0.519938 1.4986)
			(layers "F.Cu" "F.Mask" "F.Paste")
			(net "GND")
		)
		(pad "22" smd rect
			(at -2.050034 -45.47489 90)
			(size 0.519938 1.4986)
			(layers "F.Cu" "F.Mask" "F.Paste")
			(net "M_E_CPU0_SA_DQS_DP<1>")
		)
		(pad "23" smd rect
			(at -2.050034 -44.625006 90)
			(size 0.519938 1.4986)
			(layers "F.Cu" "F.Mask" "F.Paste")
			(net "M_E_CPU0_SA_DQS_DN<1>")
		)
		(pad "24" smd rect
			(at -2.050034 -43.775122 90)
			(size 0.519938 1.4986)
			(layers "F.Cu" "F.Mask" "F.Paste")
			(net "GND")
		)
		(pad "25" smd rect
			(at -2.050034 -42.924984 90)
			(size 0.519938 1.4986)
			(layers "F.Cu" "F.Mask" "F.Paste")
			(net "M_E_CPU0_SA_DQ<12>")
		)
		(pad "26" smd rect
			(at -2.050034 -42.0751 90)
			(size 0.519938 1.4986)
			(layers "F.Cu" "F.Mask" "F.Paste")
			(net "GND")
		)
		(pad "27" smd rect
			(at -2.050034 -41.224962 90)
			(size 0.519938 1.4986)
			(layers "F.Cu" "F.Mask" "F.Paste")
			(net "M_E_CPU0_SA_DQ<13>")
		)
		(pad "28" smd rect
			(at -2.050034 -40.375078 90)
			(size 0.519938 1.4986)
			(layers "F.Cu" "F.Mask" "F.Paste")
			(net "GND")
		)
		(pad "29" smd rect
			(at -2.050034 -39.52494 90)
			(size 0.519938 1.4986)
			(layers "F.Cu" "F.Mask" "F.Paste")
			(net "M_E_CPU0_SA_DQ<16>")
		)
		(pad "30" smd rect
			(at -2.050034 -38.675056 90)
			(size 0.519938 1.4986)
			(layers "F.Cu" "F.Mask" "F.Paste")
			(net "GND")
		)
		(pad "31" smd rect
			(at -2.050034 -37.824918 90)
			(size 0.519938 1.4986)
			(layers "F.Cu" "F.Mask" "F.Paste")
			(net "M_E_CPU0_SA_DQ<17>")
		)
		(pad "32" smd rect
			(at -2.050034 -36.975034 90)
			(size 0.519938 1.4986)
			(layers "F.Cu" "F.Mask" "F.Paste")
			(net "GND")
		)
		(pad "33" smd rect
			(at -2.050034 -36.124896 90)
			(size 0.519938 1.4986)
			(layers "F.Cu" "F.Mask" "F.Paste")
			(net "M_E_CPU0_SA_DQS_DP<2>")
		)
		(pad "34" smd rect
			(at -2.050034 -35.275012 90)
			(size 0.519938 1.4986)
			(layers "F.Cu" "F.Mask" "F.Paste")
			(net "M_E_CPU0_SA_DQS_DN<2>")
		)
		(pad "35" smd rect
			(at -2.050034 -34.425128 90)
			(size 0.519938 1.4986)
			(layers "F.Cu" "F.Mask" "F.Paste")
			(net "GND")
		)
		(pad "36" smd rect
			(at -2.050034 -33.57499 90)
			(size 0.519938 1.4986)
			(layers "F.Cu" "F.Mask" "F.Paste")
			(net "M_E_CPU0_SA_DQ<20>")
		)
		(pad "37" smd rect
			(at -2.050034 -32.725106 90)
			(size 0.519938 1.4986)
			(layers "F.Cu" "F.Mask" "F.Paste")
			(net "GND")
		)
		(pad "38" smd rect
			(at -2.050034 -31.874968 90)
			(size 0.519938 1.4986)
			(layers "F.Cu" "F.Mask" "F.Paste")
			(net "M_E_CPU0_SA_DQ<21>")
		)
		(pad "39" smd rect
			(at -2.050034 -31.025084 90)
			(size 0.519938 1.4986)
			(layers "F.Cu" "F.Mask" "F.Paste")
			(net "GND")
		)
		(pad "40" smd rect
			(at -2.050034 -30.174946 90)
			(size 0.519938 1.4986)
			(layers "F.Cu" "F.Mask" "F.Paste")
			(net "M_E_CPU0_SA_DQ<24>")
		)
		(pad "41" smd rect
			(at -2.050034 -29.325062 90)
			(size 0.519938 1.4986)
			(layers "F.Cu" "F.Mask" "F.Paste")
			(net "GND")
		)
		(pad "42" smd rect
			(at -2.050034 -28.474924 90)
			(size 0.519938 1.4986)
			(layers "F.Cu" "F.Mask" "F.Paste")
			(net "M_E_CPU0_SA_DQ<25>")
		)
		(pad "43" smd rect
			(at -2.050034 -27.62504 90)
			(size 0.519938 1.4986)
			(layers "F.Cu" "F.Mask" "F.Paste")
			(net "GND")
		)
		(pad "44" smd rect
			(at -2.050034 -26.774902 90)
			(size 0.519938 1.4986)
			(layers "F.Cu" "F.Mask" "F.Paste")
			(net "M_E_CPU0_SA_DQS_DP<3>")
		)
		(pad "45" smd rect
			(at -2.050034 -25.925018 90)
			(size 0.519938 1.4986)
			(layers "F.Cu" "F.Mask" "F.Paste")
			(net "M_E_CPU0_SA_DQS_DN<3>")
		)
		(pad "46" smd rect
			(at -2.050034 -25.07488 90)
			(size 0.519938 1.4986)
			(layers "F.Cu" "F.Mask" "F.Paste")
			(net "GND")
		)
	)
)
